# T6G (Grand Teton) — schematic netlist excerpt (pin names and nets, part order shuffled) for the footprints in the layout excerpt that follows; sources: Cadence DE-HDL packaged netlist, KiCad conversion of 04192023_DAF0TMB3IC0_F0TG_MB_C_brd_V02_OCP.brd

PC165  Q_CAPP  470UF 2.5V 20% SPCAP  pkg SMLF  page 205 : A = PVDDIO_P0 ; B = GND
R3484  Q_RES  33.2 1% CHIP  pkg 0402LF  page 81 : A = GPU_FPGA_OVERT_ISO_R_N ; B = GPU_FPGA_OVERT_ISO_N
R1393  Q_RES  4.7K 5% CHIP  pkg 0201LF  page 185 : A = P1V8_CPU1_RT_1D ; B = SMB_RT_CPU1_P1_ROM_MUX_2D_R_SDA

(kicad_pcb
	(version 20260206)
	(generator "pcbnew")
	(generator_version "10.0")
	(general
		(thickness 1.6)
		(legacy_teardrops no)
	)
	(paper "A4")
	(title_block
		(title "04192023_DAF0TMB3IC0_F0TG_MB_C_brd_V02_OCP.brd")
		(comment 1 "Grand Teton / footprints 7557-7559 of 8354")
	)
	(layers
		(0 "F.Cu" signal "TOP")
		(4 "In1.Cu" signal "GND")
		(6 "In2.Cu" signal "IN1")
		(8 "In3.Cu" signal "GND1")
		(10 "In4.Cu" signal "IN2")
		(12 "In5.Cu" signal "GND2")
		(14 "In6.Cu" signal "IN3")
		(16 "In7.Cu" signal "GND3")
		(18 "In8.Cu" signal "VCC")
		(20 "In9.Cu" signal "VCC1")
		(22 "In10.Cu" signal "GND4")
		(24 "In11.Cu" signal "IN4")
		(26 "In12.Cu" signal "GND5")
		(28 "In13.Cu" signal "IN5")
		(30 "In14.Cu" signal "GND6")
		(32 "In15.Cu" signal "IN6")
		(34 "In16.Cu" signal "GND7")
		(2 "B.Cu" signal "BOTTOM")
		(9 "F.Adhes" user "F.Adhesive")
		(11 "B.Adhes" user "B.Adhesive")
		(13 "F.Paste" user "Package Geometry/Pastemask Top")
		(15 "B.Paste" user "Package Geometry/Pastemask Bottom")
		(5 "F.SilkS" user "Ref Des/Silkscreen Top")
		(7 "B.SilkS" user "Ref Des/Silkscreen Bottom")
		(1 "F.Mask" user "Board Geometry/Soldermask Top")
		(3 "B.Mask" user "Board Geometry/Soldermask Bottom")
		(17 "Dwgs.User" user "User.Drawings")
		(19 "Cmts.User" user "User.Comments")
		(21 "Eco1.User" user "User.Eco1")
		(23 "Eco2.User" user "User.Eco2")
		(25 "Edge.Cuts" user "Board Geometry/Outline")
		(27 "Margin" user)
		(31 "F.CrtYd" user "Package Geometry/Place Bound Top")
		(29 "B.CrtYd" user "Package Geometry/Place Bound Bottom")
		(35 "F.Fab" user "Ref Des/Assembly Top")
		(33 "B.Fab" user "Ref Des/Assembly Bottom")
	)
	(footprint ""
		(layer "B.Cu")
		(at 200.952608 -122.769376 180)
		(property "Reference" "R3484"
			(at 0 0 0)
			(layer "B.SilkS")
			(hide yes)
			(effects
				(font
					(size 1.27 1.27)
				)
				(justify mirror)
			)
		)
		(property "Value" ""
			(at 0 0 0)
			(layer "B.Fab")
			(effects
				(font
					(size 1.27 1.27)
				)
				(justify mirror)
			)
		)
		(duplicate_pad_numbers_are_jumpers no)
		(fp_line
			(start 0.7874 0.4064)
			(end 0.7874 -0.4064)
			(stroke
				(width 0.1524)
				(type default)
			)
			(layer "B.SilkS")
		)
		(fp_line
			(start 0.7874 -0.4064)
			(end -0.7874 -0.4064)
			(stroke
				(width 0.1524)
				(type default)
			)
			(layer "B.SilkS")
		)
		(fp_line
			(start -0.7874 0.4064)
			(end 0.7874 0.4064)
			(stroke
				(width 0.1524)
				(type default)
			)
			(layer "B.SilkS")
		)
		(fp_line
			(start -0.7874 -0.4064)
			(end -0.7874 0.4064)
			(stroke
				(width 0.1524)
				(type default)
			)
			(layer "B.SilkS")
		)
		(fp_line
			(start 0.67945 0.3048)
			(end 0.67945 -0.305054)
			(stroke
				(width 0.1)
				(type default)
			)
			(layer "B.Fab")
		)
		(fp_line
			(start 0.67945 -0.305054)
			(end 0.12065 -0.305054)
			(stroke
				(width 0.1)
				(type default)
			)
			(layer "B.Fab")
		)
		(fp_line
			(start 0.12065 0.3048)
			(end 0.67945 0.3048)
			(stroke
				(width 0.1)
				(type default)
			)
			(layer "B.Fab")
		)
		(fp_line
			(start 0.12065 0.2794)
			(end 0.12065 0.3048)
			(stroke
				(width 0.1)
				(type default)
			)
			(layer "B.Fab")
		)
		(fp_line
			(start 0.12065 -0.2794)
			(end -0.12065 -0.2794)
			(stroke
				(width 0.1)
				(type default)
			)
			(layer "B.Fab")
		)
		(fp_line
			(start 0.12065 -0.305054)
			(end 0.12065 -0.2794)
			(stroke
				(width 0.1)
				(type default)
			)
			(layer "B.Fab")
		)
		(fp_line
			(start -0.120396 0.3048)
			(end -0.120396 0.2794)
			(stroke
				(width 0.1)
				(type default)
			)
			(layer "B.Fab")
		)
		(fp_line
			(start -0.120396 0.2794)
			(end 0.12065 0.2794)
			(stroke
				(width 0.1)
				(type default)
			)
			(layer "B.Fab")
		)
		(fp_line
			(start -0.12065 -0.2794)
			(end -0.12065 -0.3048)
			(stroke
				(width 0.1)
				(type default)
			)
			(layer "B.Fab")
		)
		(fp_line
			(start -0.12065 -0.3048)
			(end -0.67945 -0.3048)
			(stroke
				(width 0.1)
				(type default)
			)
			(layer "B.Fab")
		)
		(fp_line
			(start -0.67945 0.3048)
			(end -0.120396 0.3048)
			(stroke
				(width 0.1)
				(type default)
			)
			(layer "B.Fab")
		)
		(fp_line
			(start -0.67945 -0.3048)
			(end -0.67945 0.3048)
			(stroke
				(width 0.1)
				(type default)
			)
			(layer "B.Fab")
		)
		(pad "1" smd circle
			(at 0.40005 0)
			(size 0 0)
			(layers "B.Cu" "B.Mask" "B.Paste")
			(net "GPU_FPGA_OVERT_ISO_R_N")
		)
		(pad "2" smd circle
			(at -0.40005 0)
			(size 0 0)
			(layers "B.Cu" "B.Mask" "B.Paste")
			(net "GPU_FPGA_OVERT_ISO_N")
		)
	)
	(footprint ""
		(layer "B.Cu")
		(at 239.903 -336.169)
		(property "Reference" "R1393"
			(at 0 0 0)
			(layer "B.SilkS")
			(hide yes)
			(effects
				(font
					(size 1.27 1.27)
				)
				(justify mirror)
			)
		)
		(property "Value" ""
			(at 0 0 0)
			(layer "B.Fab")
			(effects
				(font
					(size 1.27 1.27)
				)
				(justify mirror)
			)
		)
		(duplicate_pad_numbers_are_jumpers no)
		(fp_line
			(start -0.32512 -0.175006)
			(end -0.32512 0.175006)
			(stroke
				(width 0.1)
				(type default)
			)
			(layer "B.Fab")
		)
		(fp_line
			(start -0.32512 0.175006)
			(end 0.32512 0.175006)
			(stroke
				(width 0.1)
				(type default)
			)
			(layer "B.Fab")
		)
		(fp_line
			(start 0.32512 -0.175006)
			(end -0.32512 -0.175006)
			(stroke
				(width 0.1)
				(type default)
			)
			(layer "B.Fab")
		)
		(fp_line
			(start 0.32512 0.175006)
			(end 0.32512 -0.175006)
			(stroke
				(width 0.1)
				(type default)
			)
			(layer "B.Fab")
		)
		(pad "1" smd rect
			(at 0.2667 0 180)
			(size 0.3048 0.381)
			(layers "B.Cu" "B.Mask" "B.Paste")
			(net "P1V8_CPU1_RT_1D")
		)
		(pad "2" smd rect
			(at -0.2667 0)
			(size 0.3048 0.381)
			(layers "B.Cu" "B.Mask" "B.Paste")
			(net "SMB_RT_CPU1_P1_ROM_MUX_2D_R_SDA")
		)
	)
	(footprint ""
		(layer "B.Cu")
		(at 284.386528 -339.910928 -90)
		(property "Reference" "PC165"
			(at 9.490456 0.924814 270)
			(unlocked yes)
			(layer "B.SilkS")
			(effects
				(font
					(size 0.7874 0.5842)
					(thickness 0.1524)
				)
				(justify left mirror)
			)
		)
		(property "Value" ""
			(at 0 0 90)
			(layer "B.Fab")
			(effects
				(font
					(size 1.27 1.27)
				)
				(justify mirror)
			)
		)
		(duplicate_pad_numbers_are_jumpers no)
		(fp_line
			(start -4.533392 2.249932)
			(end 4.533392 2.249932)
			(stroke
				(width 0.1524)
				(type default)
			)
			(layer "B.SilkS")
		)
		(fp_line
			(start 4.533392 2.249932)
			(end 4.533392 -2.249932)
			(stroke
				(width 0.1524)
				(type default)
			)
			(layer "B.SilkS")
		)
		(fp_line
			(start -4.533392 -2.249932)
			(end -4.533392 2.249932)
			(stroke
				(width 0.1524)
				(type default)
			)
			(layer "B.SilkS")
		)
		(fp_line
			(start 4.533392 -2.249932)
			(end -4.533392 -2.249932)
			(stroke
				(width 0.1524)
				(type default)
			)
			(layer "B.SilkS")
		)
		(fp_rect
			(start 5.39242 2.326132)
			(end 4.533392 -2.326132)
			(stroke
				(width 0)
				(type default)
			)
			(fill yes)
			(layer "B.SilkS")
		)
		(fp_line
			(start -3.750056 2.249932)
			(end 3.750056 2.249932)
			(stroke
				(width 0.1)
				(type default)
			)
			(layer "B.Fab")
		)
		(fp_line
			(start 3.750056 2.249932)
			(end 3.750056 -2.249932)
			(stroke
				(width 0.1)
				(type default)
			)
			(layer "B.Fab")
		)
		(fp_line
			(start -3.750056 -2.249932)
			(end -3.750056 2.249932)
			(stroke
				(width 0.1)
				(type default)
			)
			(layer "B.Fab")
		)
		(fp_line
			(start 3.750056 -2.249932)
			(end -3.750056 -2.249932)
			(stroke
				(width 0.1)
				(type default)
			)
			(layer "B.Fab")
		)
		(fp_text user "-"
			(at -4.699254 0.960374 270)
			(unlocked yes)
			(layer "B.SilkS")
			(effects
				(font
					(size 1.905 1.4224)
					(thickness 0.1524)
				)
				(justify left mirror)
			)
		)
		(fp_text user "+"
			(at 6.322314 0.786384 180)
			(unlocked yes)
			(layer "B.SilkS")
			(effects
				(font
					(size 1.905 1.4224)
					(thickness 0.1524)
				)
				(justify left mirror)
			)
		)
		(fp_text user "+"
			(at 6.322314 0.786384 180)
			(unlocked yes)
			(layer "B.Fab")
			(effects
				(font
					(size 1.905 1.4224)
					(thickness 0.1524)
				)
				(justify left mirror)
			)
		)
		(fp_text user "-"
			(at -4.8514 -0.14605 270)
			(unlocked yes)
			(layer "B.Fab")
			(effects
				(font
					(size 1.905 1.4224)
					(thickness 0.1524)
				)
				(justify left mirror)
			)
		)
		(pad "1" smd rect
			(at 3.199892 0 90)
			(size 2.413 2.8194)
			(layers "B.Cu" "B.Mask" "B.Paste")
			(net "PVDDIO_P0")
		)
		(pad "2" smd rect
			(at -3.199892 0 90)
			(size 2.413 2.8194)
			(layers "B.Cu" "B.Mask" "B.Paste")
			(net "GND")
		)
	)
)
